(kicad_pcb
	(version 20260206)
	(generator "pcbnew")
	(generator_version "10.0")
	(general
		(thickness 1.6)
		(legacy_teardrops no)
	)
	(paper "A4")
	(title_block
		(title "01162023_DA0F0TEBIF0_F0T_Expander_BD_F_brd_V02_OCP.brd")
		(comment 1 "Grand Teton / footprints 6794-6799 of 9728")
	)
	(layers
		(0 "F.Cu" signal "TOP")
		(4 "In1.Cu" signal "GND")
		(6 "In2.Cu" signal "VCC")
		(8 "In3.Cu" signal "VCC1")
		(10 "In4.Cu" signal "GND1")
		(12 "In5.Cu" signal "IN1")
		(14 "In6.Cu" signal "GND2")
		(16 "In7.Cu" signal "IN2")
		(18 "In8.Cu" signal "GND3")
		(20 "In9.Cu" signal "IN3")
		(22 "In10.Cu" signal "GND4")
		(24 "In11.Cu" signal "IN4")
		(26 "In12.Cu" signal "GND5")
		(28 "In13.Cu" signal "IN5")
		(30 "In14.Cu" signal "GND6")
		(32 "In15.Cu" signal "IN6")
		(34 "In16.Cu" signal "GND7")
		(2 "B.Cu" signal "BOTTOM")
		(9 "F.Adhes" user "F.Adhesive")
		(11 "B.Adhes" user "B.Adhesive")
		(13 "F.Paste" user "Package Geometry/Pastemask Top")
		(15 "B.Paste" user "Package Geometry/Pastemask Bottom")
		(5 "F.SilkS" user "Ref Des/Silkscreen Top")
		(7 "B.SilkS" user "Ref Des/Silkscreen Bottom")
		(1 "F.Mask" user "Board Geometry/Soldermask Top")
		(3 "B.Mask" user "Board Geometry/Soldermask Bottom")
		(17 "Dwgs.User" user "User.Drawings")
		(19 "Cmts.User" user "User.Comments")
		(21 "Eco1.User" user "User.Eco1")
		(23 "Eco2.User" user "User.Eco2")
		(25 "Edge.Cuts" user "Board Geometry/Outline")
		(27 "Margin" user)
		(31 "F.CrtYd" user "Package Geometry/Place Bound Top")
		(29 "B.CrtYd" user "Package Geometry/Place Bound Bottom")
		(35 "F.Fab" user "Ref Des/Assembly Top")
		(33 "B.Fab" user "Ref Des/Assembly Bottom")
	)
	(footprint ""
		(layer "F.Cu")
		(at 194.343782 -49.95291 180)
		(property "Reference" "R5896"
			(at 0 0 180)
			(layer "F.SilkS")
			(hide yes)
			(effects
				(font
					(size 1.27 1.27)
				)
			)
		)
		(property "Value" ""
			(at 0 0 180)
			(layer "F.Fab")
			(effects
				(font
					(size 1.27 1.27)
				)
			)
		)
		(duplicate_pad_numbers_are_jumpers no)
		(fp_line
			(start 0.7874 0.4064)
			(end -0.7874 0.4064)
			(stroke
				(width 0.1524)
				(type default)
			)
			(layer "F.SilkS")
		)
		(fp_line
			(start 0.7874 -0.4064)
			(end 0.7874 0.4064)
			(stroke
				(width 0.1524)
				(type default)
			)
			(layer "F.SilkS")
		)
		(fp_line
			(start -0.7874 0.4064)
			(end -0.7874 -0.4064)
			(stroke
				(width 0.1524)
				(type default)
			)
			(layer "F.SilkS")
		)
		(fp_line
			(start -0.7874 -0.4064)
			(end 0.7874 -0.4064)
			(stroke
				(width 0.1524)
				(type default)
			)
			(layer "F.SilkS")
		)
		(fp_line
			(start 0.67945 0.3048)
			(end 0.120396 0.3048)
			(stroke
				(width 0.1)
				(type default)
			)
			(layer "F.Fab")
		)
		(fp_line
			(start 0.67945 -0.3048)
			(end 0.67945 0.3048)
			(stroke
				(width 0.1)
				(type default)
			)
			(layer "F.Fab")
		)
		(fp_line
			(start 0.12065 -0.2794)
			(end 0.12065 -0.3048)
			(stroke
				(width 0.1)
				(type default)
			)
			(layer "F.Fab")
		)
		(fp_line
			(start 0.12065 -0.3048)
			(end 0.67945 -0.3048)
			(stroke
				(width 0.1)
				(type default)
			)
			(layer "F.Fab")
		)
		(fp_line
			(start 0.120396 0.3048)
			(end 0.120396 0.2794)
			(stroke
				(width 0.1)
				(type default)
			)
			(layer "F.Fab")
		)
		(fp_line
			(start 0.120396 0.2794)
			(end -0.12065 0.2794)
			(stroke
				(width 0.1)
				(type default)
			)
			(layer "F.Fab")
		)
		(fp_line
			(start -0.12065 0.3048)
			(end -0.67945 0.3048)
			(stroke
				(width 0.1)
				(type default)
			)
			(layer "F.Fab")
		)
		(fp_line
			(start -0.12065 0.2794)
			(end -0.12065 0.3048)
			(stroke
				(width 0.1)
				(type default)
			)
			(layer "F.Fab")
		)
		(fp_line
			(start -0.12065 -0.2794)
			(end 0.12065 -0.2794)
			(stroke
				(width 0.1)
				(type default)
			)
			(layer "F.Fab")
		)
		(fp_line
			(start -0.12065 -0.305054)
			(end -0.12065 -0.2794)
			(stroke
				(width 0.1)
				(type default)
			)
			(layer "F.Fab")
		)
		(fp_line
			(start -0.67945 0.3048)
			(end -0.67945 -0.305054)
			(stroke
				(width 0.1)
				(type default)
			)
			(layer "F.Fab")
		)
		(fp_line
			(start -0.67945 -0.305054)
			(end -0.12065 -0.305054)
			(stroke
				(width 0.1)
				(type default)
			)
			(layer "F.Fab")
		)
		(pad "1" smd circle
			(at -0.40005 0 180)
			(size 0 0)
			(layers "F.Cu" "F.Mask" "F.Paste")
			(net "SSD6_ADC_A0")
		)
		(pad "2" smd circle
			(at 0.40005 0 180)
			(size 0 0)
			(layers "F.Cu" "F.Mask" "F.Paste")
			(net "SMB_SSD6_ADC_SDA")
		)
	)
	(footprint ""
		(layer "F.Cu")
		(at 46.434502 -30.03169 180)
		(property "Reference" "C78"
			(at 0 0 180)
			(layer "F.SilkS")
			(hide yes)
			(effects
				(font
					(size 1.27 1.27)
				)
			)
		)
		(property "Value" ""
			(at 0 0 180)
			(layer "F.Fab")
			(effects
				(font
					(size 1.27 1.27)
				)
			)
		)
		(duplicate_pad_numbers_are_jumpers no)
		(fp_line
			(start 0.299974 0.150114)
			(end -0.299974 0.150114)
			(stroke
				(width 0.1)
				(type default)
			)
			(layer "F.Fab")
		)
		(fp_line
			(start 0.299974 -0.150114)
			(end 0.299974 0.150114)
			(stroke
				(width 0.1)
				(type default)
			)
			(layer "F.Fab")
		)
		(fp_line
			(start -0.299974 0.150114)
			(end -0.299974 -0.150114)
			(stroke
				(width 0.1)
				(type default)
			)
			(layer "F.Fab")
		)
		(fp_line
			(start -0.299974 -0.150114)
			(end 0.299974 -0.150114)
			(stroke
				(width 0.1)
				(type default)
			)
			(layer "F.Fab")
		)
		(pad "1" smd rect
			(at -0.2667 0 180)
			(size 0.3048 0.381)
			(layers "F.Cu" "F.Mask" "F.Paste")
			(net "P5E_PEX0_STN2_TX_DN<41>")
		)
		(pad "2" smd rect
			(at 0.2667 0 180)
			(size 0.3048 0.381)
			(layers "F.Cu" "F.Mask" "F.Paste")
			(net "P5E_PEX0_STN2_TX_C_DN<41>")
		)
	)
	(footprint ""
		(layer "F.Cu")
		(at 130.09118 -280.44902 -90)
		(property "Reference" "PR112"
			(at 0 0 270)
			(layer "F.SilkS")
			(hide yes)
			(effects
				(font
					(size 1.27 1.27)
				)
			)
		)
		(property "Value" ""
			(at 0 0 270)
			(layer "F.Fab")
			(effects
				(font
					(size 1.27 1.27)
				)
			)
		)
		(duplicate_pad_numbers_are_jumpers no)
		(fp_line
			(start -0.7874 0.4064)
			(end -0.7874 -0.4064)
			(stroke
				(width 0.1524)
				(type default)
			)
			(layer "F.SilkS")
		)
		(fp_line
			(start 0.7874 0.4064)
			(end -0.7874 0.4064)
			(stroke
				(width 0.1524)
				(type default)
			)
			(layer "F.SilkS")
		)
		(fp_line
			(start -0.7874 -0.4064)
			(end 0.7874 -0.4064)
			(stroke
				(width 0.1524)
				(type default)
			)
			(layer "F.SilkS")
		)
		(fp_line
			(start 0.7874 -0.4064)
			(end 0.7874 0.4064)
			(stroke
				(width 0.1524)
				(type default)
			)
			(layer "F.SilkS")
		)
		(fp_line
			(start -0.67945 0.3048)
			(end -0.67945 -0.305054)
			(stroke
				(width 0.1)
				(type default)
			)
			(layer "F.Fab")
		)
		(fp_line
			(start -0.12065 0.3048)
			(end -0.67945 0.3048)
			(stroke
				(width 0.1)
				(type default)
			)
			(layer "F.Fab")
		)
		(fp_line
			(start 0.120396 0.3048)
			(end 0.120396 0.2794)
			(stroke
				(width 0.1)
				(type default)
			)
			(layer "F.Fab")
		)
		(fp_line
			(start 0.67945 0.3048)
			(end 0.120396 0.3048)
			(stroke
				(width 0.1)
				(type default)
			)
			(layer "F.Fab")
		)
		(fp_line
			(start -0.12065 0.2794)
			(end -0.12065 0.3048)
			(stroke
				(width 0.1)
				(type default)
			)
			(layer "F.Fab")
		)
		(fp_line
			(start 0.120396 0.2794)
			(end -0.12065 0.2794)
			(stroke
				(width 0.1)
				(type default)
			)
			(layer "F.Fab")
		)
		(fp_line
			(start -0.12065 -0.2794)
			(end 0.12065 -0.2794)
			(stroke
				(width 0.1)
				(type default)
			)
			(layer "F.Fab")
		)
		(fp_line
			(start 0.12065 -0.2794)
			(end 0.12065 -0.3048)
			(stroke
				(width 0.1)
				(type default)
			)
			(layer "F.Fab")
		)
		(fp_line
			(start 0.12065 -0.3048)
			(end 0.67945 -0.3048)
			(stroke
				(width 0.1)
				(type default)
			)
			(layer "F.Fab")
		)
		(fp_line
			(start 0.67945 -0.3048)
			(end 0.67945 0.3048)
			(stroke
				(width 0.1)
				(type default)
			)
			(layer "F.Fab")
		)
		(fp_line
			(start -0.67945 -0.305054)
			(end -0.12065 -0.305054)
			(stroke
				(width 0.1)
				(type default)
			)
			(layer "F.Fab")
		)
		(fp_line
			(start -0.12065 -0.305054)
			(end -0.12065 -0.2794)
			(stroke
				(width 0.1)
				(type default)
			)
			(layer "F.Fab")
		)
		(pad "1" smd circle
			(at -0.40005 0 270)
			(size 0 0)
			(layers "F.Cu" "F.Mask" "F.Paste")
			(net "SW_P0V8_PEX1_BOOT2")
		)
		(pad "2" smd circle
			(at 0.40005 0 270)
			(size 0 0)
			(layers "F.Cu" "F.Mask" "F.Paste")
			(net "SW_P0V8_PEX1_BOOT2_R")
		)
	)
	(footprint ""
		(layer "F.Cu")
		(at 372.415562 -42.853102 180)
		(property "Reference" "R5904"
			(at 0 0 180)
			(layer "F.SilkS")
			(hide yes)
			(effects
				(font
					(size 1.27 1.27)
				)
			)
		)
		(property "Value" ""
			(at 0 0 180)
			(layer "F.Fab")
			(effects
				(font
					(size 1.27 1.27)
				)
			)
		)
		(duplicate_pad_numbers_are_jumpers no)
		(fp_line
			(start 0.7874 0.4064)
			(end -0.7874 0.4064)
			(stroke
				(width 0.1524)
				(type default)
			)
			(layer "F.SilkS")
		)
		(fp_line
			(start 0.7874 -0.4064)
			(end 0.7874 0.4064)
			(stroke
				(width 0.1524)
				(type default)
			)
			(layer "F.SilkS")
		)
		(fp_line
			(start -0.7874 0.4064)
			(end -0.7874 -0.4064)
			(stroke
				(width 0.1524)
				(type default)
			)
			(layer "F.SilkS")
		)
		(fp_line
			(start -0.7874 -0.4064)
			(end 0.7874 -0.4064)
			(stroke
				(width 0.1524)
				(type default)
			)
			(layer "F.SilkS")
		)
		(fp_line
			(start 0.67945 0.3048)
			(end 0.120396 0.3048)
			(stroke
				(width 0.1)
				(type default)
			)
			(layer "F.Fab")
		)
		(fp_line
			(start 0.67945 -0.3048)
			(end 0.67945 0.3048)
			(stroke
				(width 0.1)
				(type default)
			)
			(layer "F.Fab")
		)
		(fp_line
			(start 0.12065 -0.2794)
			(end 0.12065 -0.3048)
			(stroke
				(width 0.1)
				(type default)
			)
			(layer "F.Fab")
		)
		(fp_line
			(start 0.12065 -0.3048)
			(end 0.67945 -0.3048)
			(stroke
				(width 0.1)
				(type default)
			)
			(layer "F.Fab")
		)
		(fp_line
			(start 0.120396 0.3048)
			(end 0.120396 0.2794)
			(stroke
				(width 0.1)
				(type default)
			)
			(layer "F.Fab")
		)
		(fp_line
			(start 0.120396 0.2794)
			(end -0.12065 0.2794)
			(stroke
				(width 0.1)
				(type default)
			)
			(layer "F.Fab")
		)
		(fp_line
			(start -0.12065 0.3048)
			(end -0.67945 0.3048)
			(stroke
				(width 0.1)
				(type default)
			)
			(layer "F.Fab")
		)
		(fp_line
			(start -0.12065 0.2794)
			(end -0.12065 0.3048)
			(stroke
				(width 0.1)
				(type default)
			)
			(layer "F.Fab")
		)
		(fp_line
			(start -0.12065 -0.2794)
			(end 0.12065 -0.2794)
			(stroke
				(width 0.1)
				(type default)
			)
			(layer "F.Fab")
		)
		(fp_line
			(start -0.12065 -0.305054)
			(end -0.12065 -0.2794)
			(stroke
				(width 0.1)
				(type default)
			)
			(layer "F.Fab")
		)
		(fp_line
			(start -0.67945 0.3048)
			(end -0.67945 -0.305054)
			(stroke
				(width 0.1)
				(type default)
			)
			(layer "F.Fab")
		)
		(fp_line
			(start -0.67945 -0.305054)
			(end -0.12065 -0.305054)
			(stroke
				(width 0.1)
				(type default)
			)
			(layer "F.Fab")
		)
		(pad "1" smd circle
			(at -0.40005 0 180)
			(size 0 0)
			(layers "F.Cu" "F.Mask" "F.Paste")
			(net "SSD12_ADC_A1")
		)
		(pad "2" smd circle
			(at 0.40005 0 180)
			(size 0 0)
			(layers "F.Cu" "F.Mask" "F.Paste")
			(net "SMB_SSD12_ADC_SCL")
		)
	)
	(footprint ""
		(layer "F.Cu")
		(at 15.59052 -305.808634 -90)
		(property "Reference" "PC978"
			(at 0 0 270)
			(layer "F.SilkS")
			(hide yes)
			(effects
				(font
					(size 1.27 1.27)
				)
			)
		)
		(property "Value" ""
			(at 0 0 270)
			(layer "F.Fab")
			(effects
				(font
					(size 1.27 1.27)
				)
			)
		)
		(duplicate_pad_numbers_are_jumpers no)
		(fp_line
			(start -0.7874 0.4064)
			(end -0.7874 -0.4064)
			(stroke
				(width 0.1524)
				(type default)
			)
			(layer "F.SilkS")
		)
		(fp_line
			(start 0.7874 0.4064)
			(end -0.7874 0.4064)
			(stroke
				(width 0.1524)
				(type default)
			)
			(layer "F.SilkS")
		)
		(fp_line
			(start -0.7874 -0.4064)
			(end 0.7874 -0.4064)
			(stroke
				(width 0.1524)
				(type default)
			)
			(layer "F.SilkS")
		)
		(fp_line
			(start 0.7874 -0.4064)
			(end 0.7874 0.4064)
			(stroke
				(width 0.1524)
				(type default)
			)
			(layer "F.SilkS")
		)
		(fp_line
			(start -0.67945 0.3048)
			(end -0.67945 -0.305054)
			(stroke
				(width 0.1)
				(type default)
			)
			(layer "F.Fab")
		)
		(fp_line
			(start -0.12065 0.3048)
			(end -0.67945 0.3048)
			(stroke
				(width 0.1)
				(type default)
			)
			(layer "F.Fab")
		)
		(fp_line
			(start 0.120396 0.3048)
			(end 0.120396 0.2794)
			(stroke
				(width 0.1)
				(type default)
			)
			(layer "F.Fab")
		)
		(fp_line
			(start 0.67945 0.3048)
			(end 0.120396 0.3048)
			(stroke
				(width 0.1)
				(type default)
			)
			(layer "F.Fab")
		)
		(fp_line
			(start -0.12065 0.2794)
			(end -0.12065 0.3048)
			(stroke
				(width 0.1)
				(type default)
			)
			(layer "F.Fab")
		)
		(fp_line
			(start 0.120396 0.2794)
			(end -0.12065 0.2794)
			(stroke
				(width 0.1)
				(type default)
			)
			(layer "F.Fab")
		)
		(fp_line
			(start -0.12065 -0.2794)
			(end 0.12065 -0.2794)
			(stroke
				(width 0.1)
				(type default)
			)
			(layer "F.Fab")
		)
		(fp_line
			(start 0.12065 -0.2794)
			(end 0.12065 -0.3048)
			(stroke
				(width 0.1)
				(type default)
			)
			(layer "F.Fab")
		)
		(fp_line
			(start 0.12065 -0.3048)
			(end 0.67945 -0.3048)
			(stroke
				(width 0.1)
				(type default)
			)
			(layer "F.Fab")
		)
		(fp_line
			(start 0.67945 -0.3048)
			(end 0.67945 0.3048)
			(stroke
				(width 0.1)
				(type default)
			)
			(layer "F.Fab")
		)
		(fp_line
			(start -0.67945 -0.305054)
			(end -0.12065 -0.305054)
			(stroke
				(width 0.1)
				(type default)
			)
			(layer "F.Fab")
		)
		(fp_line
			(start -0.12065 -0.305054)
			(end -0.12065 -0.2794)
			(stroke
				(width 0.1)
				(type default)
			)
			(layer "F.Fab")
		)
		(pad "1" smd circle
			(at -0.40005 0 270)
			(size 0 0)
			(layers "F.Cu" "F.Mask" "F.Paste")
			(net "SH_P1V25_PEX0_FB_P")
		)
		(pad "2" smd circle
			(at 0.40005 0 270)
			(size 0 0)
			(layers "F.Cu" "F.Mask" "F.Paste")
			(net "SH_P1V25_PEX0_FB_N")
		)
	)
	(footprint ""
		(layer "F.Cu")
		(at 260.305042 -307.084984 45)
		(property "Reference" "R1349"
			(at 0 0 45)
			(layer "F.SilkS")
			(hide yes)
			(effects
				(font
					(size 1.27 1.27)
				)
			)
		)
		(property "Value" ""
			(at 0 0 45)
			(layer "F.Fab")
			(effects
				(font
					(size 1.27 1.27)
				)
			)
		)
		(duplicate_pad_numbers_are_jumpers no)
		(fp_line
			(start -0.787389 -0.406267)
			(end 0.787389 -0.406267)
			(stroke
				(width 0.1524)
				(type default)
			)
			(layer "F.SilkS")
		)
		(fp_line
			(start -0.787389 0.406267)
			(end -0.787389 -0.406267)
			(stroke
				(width 0.1524)
				(type default)
			)
			(layer "F.SilkS")
		)
		(fp_line
			(start 0.787389 -0.406267)
			(end 0.787389 0.406267)
			(stroke
				(width 0.1524)
				(type default)
			)
			(layer "F.SilkS")
		)
		(fp_line
			(start 0.787389 0.406267)
			(end -0.787389 0.406267)
			(stroke
				(width 0.1524)
				(type default)
			)
			(layer "F.SilkS")
		)
		(fp_line
			(start -0.679446 -0.305149)
			(end -0.120695 -0.304969)
			(stroke
				(width 0.1)
				(type default)
			)
			(layer "F.Fab")
		)
		(fp_line
			(start -0.120695 -0.304969)
			(end -0.120695 -0.279466)
			(stroke
				(width 0.1)
				(type default)
			)
			(layer "F.Fab")
		)
		(fp_line
			(start -0.120695 -0.279466)
			(end 0.120695 -0.279466)
			(stroke
				(width 0.1)
				(type default)
			)
			(layer "F.Fab")
		)
		(fp_line
			(start -0.679446 0.30479)
			(end -0.679446 -0.305149)
			(stroke
				(width 0.1)
				(type default)
			)
			(layer "F.Fab")
		)
		(fp_line
			(start 0.120515 -0.30479)
			(end 0.679446 -0.30479)
			(stroke
				(width 0.1)
				(type default)
			)
			(layer "F.Fab")
		)
		(fp_line
			(start 0.120695 -0.279466)
			(end 0.120515 -0.30479)
			(stroke
				(width 0.1)
				(type default)
			)
			(layer "F.Fab")
		)
		(fp_line
			(start -0.120695 0.279466)
			(end -0.120515 0.30479)
			(stroke
				(width 0.1)
				(type default)
			)
			(layer "F.Fab")
		)
		(fp_line
			(start -0.120515 0.30479)
			(end -0.679446 0.30479)
			(stroke
				(width 0.1)
				(type default)
			)
			(layer "F.Fab")
		)
		(fp_line
			(start 0.679446 -0.30479)
			(end 0.679446 0.30479)
			(stroke
				(width 0.1)
				(type default)
			)
			(layer "F.Fab")
		)
		(fp_line
			(start 0.120335 0.279466)
			(end -0.120695 0.279466)
			(stroke
				(width 0.1)
				(type default)
			)
			(layer "F.Fab")
		)
		(fp_line
			(start 0.120515 0.30479)
			(end 0.120335 0.279466)
			(stroke
				(width 0.1)
				(type default)
			)
			(layer "F.Fab")
		)
		(fp_line
			(start 0.679446 0.30479)
			(end 0.120515 0.30479)
			(stroke
				(width 0.1)
				(type default)
			)
			(layer "F.Fab")
		)
		(pad "1" smd circle
			(at -0.40005 0 45)
			(size 0 0)
			(layers "F.Cu" "F.Mask" "F.Paste")
			(net "GND")
		)
		(pad "2" smd circle
			(at 0.40005 0 45)
			(size 0 0)
			(layers "F.Cu" "F.Mask" "F.Paste")
			(net "PEX2_DBG_SEL0")
		)
	)
)
